(kicad_pcb
	(version 20260206)
	(generator "pcbnew")
	(generator_version "10.0")
	(general
		(thickness 1.6)
		(legacy_teardrops no)
	)
	(paper "A4")
	(title_block
		(title "Bryce Canyon_F.DPB_16315-1-OCP.brd")
		(comment 1 "Bryce Canyon / footprints 172-178 of 2223")
	)
	(layers
		(0 "F.Cu" signal "TOP")
		(4 "In1.Cu" signal "L2GND")
		(6 "In2.Cu" signal "L3")
		(8 "In3.Cu" signal "L4GND")
		(10 "In4.Cu" signal "L5")
		(12 "In5.Cu" signal "L6VCC")
		(14 "In6.Cu" signal "L7VCC")
		(16 "In7.Cu" signal "L8")
		(18 "In8.Cu" signal "L9GND")
		(20 "In9.Cu" signal "L10")
		(22 "In10.Cu" signal "L11GND")
		(2 "B.Cu" signal "BOTTOM")
		(9 "F.Adhes" user "F.Adhesive")
		(11 "B.Adhes" user "B.Adhesive")
		(13 "F.Paste" user "Package Geometry/Pastemask Top")
		(15 "B.Paste" user "Package Geometry/Pastemask Bottom")
		(5 "F.SilkS" user "Ref Des/Silkscreen Top")
		(7 "B.SilkS" user "Ref Des/Silkscreen Bottom")
		(1 "F.Mask" user "Board Geometry/Soldermask Top")
		(3 "B.Mask" user "Board Geometry/Soldermask Bottom")
		(17 "Dwgs.User" user "User.Drawings")
		(19 "Cmts.User" user "User.Comments")
		(21 "Eco1.User" user "User.Eco1")
		(23 "Eco2.User" user "User.Eco2")
		(25 "Edge.Cuts" user "Board Geometry/Outline")
		(27 "Margin" user)
		(31 "F.CrtYd" user "Package Geometry/Place Bound Top")
		(29 "B.CrtYd" user "Package Geometry/Place Bound Bottom")
		(35 "F.Fab" user "Ref Des/Assembly Top")
		(33 "B.Fab" user "Ref Des/Assembly Bottom")
	)
	(footprint ""
		(layer "F.Cu")
		(at 334.899 -167.872918 -90)
		(property "Reference" "Q108"
			(at 0 0 270)
			(layer "F.SilkS")
			(hide yes)
			(effects
				(font
					(size 1.27 1.27)
				)
			)
		)
		(property "Value" "AO4406AL-GP"
			(at -3.707384 -1.5367 270)
			(unlocked yes)
			(layer "F.Fab")
			(hide yes)
			(effects
				(font
					(size 1.016 1.016)
					(thickness 0.1524)
				)
			)
		)
		(property "Device Type" "SOIC8H69"
			(at -3.707384 -3.0607 270)
			(unlocked yes)
			(layer "F.Fab")
			(hide yes)
			(effects
				(font
					(size 1.016 1.016)
					(thickness 0.1524)
				)
			)
		)
		(duplicate_pad_numbers_are_jumpers no)
		(fp_line
			(start -2.6289 3.4417)
			(end -2.6289 1.4732)
			(stroke
				(width 0.381)
				(type default)
			)
			(layer "F.SilkS")
		)
		(fp_line
			(start -2.7432 1.4224)
			(end -2.6416 1.4224)
			(stroke
				(width 0.1524)
				(type default)
			)
			(layer "F.SilkS")
		)
		(fp_line
			(start -2.7432 1.4224)
			(end 2.1336 1.4224)
			(stroke
				(width 0.1524)
				(type default)
			)
			(layer "F.SilkS")
		)
		(fp_line
			(start 2.1336 1.4224)
			(end 2.1336 -1.4224)
			(stroke
				(width 0.1524)
				(type default)
			)
			(layer "F.SilkS")
		)
		(fp_line
			(start -2.1844 -0.0508)
			(end -2.7178 0.508)
			(stroke
				(width 0.1524)
				(type default)
			)
			(layer "F.SilkS")
		)
		(fp_line
			(start -2.7178 -0.508)
			(end -2.1844 -0.0508)
			(stroke
				(width 0.1524)
				(type default)
			)
			(layer "F.SilkS")
		)
		(fp_line
			(start -2.7432 -1.4224)
			(end -2.7432 1.4224)
			(stroke
				(width 0.1524)
				(type default)
			)
			(layer "F.SilkS")
		)
		(fp_line
			(start 2.1336 -1.4224)
			(end -2.7432 -1.4224)
			(stroke
				(width 0.1524)
				(type default)
			)
			(layer "F.SilkS")
		)
		(fp_poly
			(pts
				(xy -2.2098 -1.4224) (xy -2.2098 1.4224) (xy 2.2098 1.4224) (xy 2.2098 -1.4224)
			)
			(stroke
				(width 0)
				(type default)
			)
			(fill yes)
			(layer "F.SilkS")
		)
		(fp_rect
			(start -2.450084 2.999994)
			(end 2.450084 -2.999994)
			(stroke
				(width 0)
				(type default)
			)
			(fill no)
			(layer "F.CrtYd")
		)
		(fp_poly
			(pts
				(xy -2.8194 3.6322) (xy -2.8194 -3.6322) (xy 2.8194 -3.6322) (xy 2.8194 1.18364) (xy 2.450084 1.18364)
				(xy 2.450084 -2.999994) (xy -2.450084 -2.999994) (xy -2.450084 2.999994) (xy 2.450084 2.999994)
				(xy 2.450084 1.18618) (xy 2.8194 1.18618) (xy 2.8194 3.6322)
			)
			(stroke
				(width 0)
				(type default)
			)
			(fill no)
			(layer "F.CrtYd")
		)
		(fp_rect
			(start -2.8194 3.6322)
			(end 2.8194 -3.6322)
			(stroke
				(width 0)
				(type default)
			)
			(fill no)
			(layer "F.Fab")
		)
		(pad "1" smd rect
			(at -1.905 2.54 270)
			(size 0.635 1.651)
			(layers "F.Cu" "F.Mask" "F.Paste")
			(net "P5V_HDD18")
		)
		(pad "2" smd rect
			(at -0.635 2.54 270)
			(size 0.635 1.651)
			(layers "F.Cu" "F.Mask" "F.Paste")
			(net "P5V_HDD18")
		)
		(pad "3" smd rect
			(at 0.635 2.54 270)
			(size 0.635 1.651)
			(layers "F.Cu" "F.Mask" "F.Paste")
			(net "P5V_HDD18")
		)
		(pad "4" smd rect
			(at 1.905 2.54 270)
			(size 0.635 1.651)
			(layers "F.Cu" "F.Mask" "F.Paste")
			(net "SW_HDD_P18")
		)
		(pad "5" smd rect
			(at 1.905 -2.54 270)
			(size 0.635 1.651)
			(layers "F.Cu" "F.Mask" "F.Paste")
			(net "P5V_A_3")
		)
		(pad "6" smd rect
			(at 0.635 -2.54 270)
			(size 0.635 1.651)
			(layers "F.Cu" "F.Mask" "F.Paste")
			(net "P5V_A_3")
		)
		(pad "7" smd rect
			(at -0.635 -2.54 270)
			(size 0.635 1.651)
			(layers "F.Cu" "F.Mask" "F.Paste")
			(net "P5V_A_3")
		)
		(pad "8" smd rect
			(at -1.905 -2.54 270)
			(size 0.635 1.651)
			(layers "F.Cu" "F.Mask" "F.Paste")
			(net "P5V_A_3")
		)
	)
	(footprint ""
		(layer "F.Cu")
		(at 114.699796 -61.000894 -90)
		(property "Reference" "C392"
			(at 0 0 270)
			(layer "F.SilkS")
			(hide yes)
			(effects
				(font
					(size 1.27 1.27)
				)
			)
		)
		(property "Value" "SC10U16V6KX-2GP"
			(at -0.0762 -5.1308 270)
			(unlocked yes)
			(layer "F.Fab")
			(hide yes)
			(effects
				(font
					(size 1.016 1.016)
					(thickness 0.1524)
				)
			)
		)
		(property "Device Type" "C1206H71"
			(at -0.127 -6.6548 270)
			(unlocked yes)
			(layer "F.Fab")
			(hide yes)
			(effects
				(font
					(size 1.016 1.016)
					(thickness 0.1524)
				)
			)
		)
		(duplicate_pad_numbers_are_jumpers no)
		(fp_line
			(start -1.016 2.2352)
			(end -1.016 0.8382)
			(stroke
				(width 0.1524)
				(type default)
			)
			(layer "F.SilkS")
		)
		(fp_line
			(start 1.016 2.2352)
			(end -1.016 2.2352)
			(stroke
				(width 0.1524)
				(type default)
			)
			(layer "F.SilkS")
		)
		(fp_line
			(start 1.016 0.8382)
			(end 1.016 2.2352)
			(stroke
				(width 0.1524)
				(type default)
			)
			(layer "F.SilkS")
		)
		(fp_line
			(start -1.016 -0.8382)
			(end -1.016 -2.2352)
			(stroke
				(width 0.1524)
				(type default)
			)
			(layer "F.SilkS")
		)
		(fp_line
			(start -1.016 -2.2352)
			(end 1.016 -2.2352)
			(stroke
				(width 0.1524)
				(type default)
			)
			(layer "F.SilkS")
		)
		(fp_line
			(start 1.016 -2.2352)
			(end 1.016 -0.8382)
			(stroke
				(width 0.1524)
				(type default)
			)
			(layer "F.SilkS")
		)
		(fp_rect
			(start -1.0922 2.3114)
			(end 1.0922 -2.3114)
			(stroke
				(width 0)
				(type default)
			)
			(fill no)
			(layer "F.CrtYd")
		)
		(fp_poly
			(pts
				(xy 1.0922 -2.3114) (xy 1.0922 2.3114) (xy -1.0922 2.3114) (xy -1.0922 -2.3114)
			)
			(stroke
				(width 0)
				(type default)
			)
			(fill no)
			(layer "F.Fab")
		)
		(pad "1" smd rect
			(at 0 -1.397 270)
			(size 1.651 1.27)
			(layers "F.Cu" "F.Mask" "F.Paste")
			(net "P5V_HDD27")
		)
		(pad "2" smd rect
			(at 0 1.397 270)
			(size 1.651 1.27)
			(layers "F.Cu" "F.Mask" "F.Paste")
			(net "GND")
		)
	)
	(footprint ""
		(layer "F.Cu")
		(at 174.498 -280.993342 90)
		(property "Reference" "R252"
			(at 0 0 90)
			(layer "F.SilkS")
			(hide yes)
			(effects
				(font
					(size 1.27 1.27)
				)
			)
		)
		(property "Value" "4K7R2J-2-GP"
			(at 0.064008 -3.993896 90)
			(unlocked yes)
			(layer "F.Fab")
			(hide yes)
			(effects
				(font
					(size 1.016 1.016)
					(thickness 0.1524)
				)
			)
		)
		(property "Device Type" "R402H16"
			(at 0.064008 -5.517896 90)
			(unlocked yes)
			(layer "F.Fab")
			(hide yes)
			(effects
				(font
					(size 1.016 1.016)
					(thickness 0.1524)
				)
			)
		)
		(duplicate_pad_numbers_are_jumpers no)
		(fp_line
			(start 0.508 -0.9398)
			(end -0.508 -0.9398)
			(stroke
				(width 0.1524)
				(type default)
			)
			(layer "F.SilkS")
		)
		(fp_line
			(start -0.508 -0.9398)
			(end -0.508 0.9398)
			(stroke
				(width 0.1524)
				(type default)
			)
			(layer "F.SilkS")
		)
		(fp_rect
			(start -0.508 0.9398)
			(end 0.508 -0.9398)
			(stroke
				(width 0)
				(type default)
			)
			(fill no)
			(layer "F.CrtYd")
		)
		(fp_rect
			(start -0.508 0.9398)
			(end 0.508 -0.9398)
			(stroke
				(width 0)
				(type default)
			)
			(fill no)
			(layer "F.Fab")
		)
		(pad "1" smd custom
			(at 0 -0.4445 90)
			(size 0.1397 0.1397)
			(layers "F.Cu" "F.Mask" "F.Paste")
			(net "P12V_A")
			(options
				(clearance outline)
				(anchor circle)
			)
			(primitives
				(gr_poly
					(pts
						(arc
							(start -0.1778 -0.2794)
							(mid -0.249642 -0.249642)
							(end -0.2794 -0.1778)
						)
						(arc
							(start -0.2794 0.1778)
							(mid -0.249642 0.249642)
							(end -0.1778 0.2794)
						)
						(arc
							(start 0.1778 0.2794)
							(mid 0.249642 0.249642)
							(end 0.2794 0.1778)
						)
						(arc
							(start 0.2794 -0.1778)
							(mid 0.249642 -0.249642)
							(end 0.1778 -0.2794)
						)
					)
					(width 0)
					(fill yes)
				)
			)
		)
		(pad "2" smd custom
			(at 0 0.4445 90)
			(size 0.1397 0.1397)
			(layers "F.Cu" "F.Mask" "F.Paste")
			(net "SW_HDD_P5")
			(options
				(clearance outline)
				(anchor circle)
			)
			(primitives
				(gr_poly
					(pts
						(arc
							(start -0.1778 -0.2794)
							(mid -0.249642 -0.249642)
							(end -0.2794 -0.1778)
						)
						(arc
							(start -0.2794 0.1778)
							(mid -0.249642 0.249642)
							(end -0.1778 0.2794)
						)
						(arc
							(start 0.1778 0.2794)
							(mid 0.249642 0.249642)
							(end 0.2794 0.1778)
						)
						(arc
							(start 0.2794 -0.1778)
							(mid 0.249642 -0.249642)
							(end 0.1778 -0.2794)
						)
					)
					(width 0)
					(fill yes)
				)
			)
		)
	)
	(footprint ""
		(layer "F.Cu")
		(at 36.178998 -65.064894 90)
		(property "Reference" "R686"
			(at 0 0 90)
			(layer "F.SilkS")
			(hide yes)
			(effects
				(font
					(size 1.27 1.27)
				)
			)
		)
		(property "Value" "220R3F-1-GP"
			(at -0.0254 -2.5146 90)
			(unlocked yes)
			(layer "F.Fab")
			(hide yes)
			(effects
				(font
					(size 1.016 1.016)
					(thickness 0.1524)
				)
			)
		)
		(property "Device Type" "R603H22"
			(at -0.0254 -4.0386 90)
			(unlocked yes)
			(layer "F.Fab")
			(hide yes)
			(effects
				(font
					(size 1.016 1.016)
					(thickness 0.1524)
				)
			)
		)
		(duplicate_pad_numbers_are_jumpers no)
		(fp_line
			(start 0.2032 0)
			(end 0.4826 0)
			(stroke
				(width 0.2032)
				(type default)
			)
			(layer "F.SilkS")
		)
		(fp_line
			(start -0.4826 0)
			(end -0.2032 0)
			(stroke
				(width 0.2032)
				(type default)
			)
			(layer "F.SilkS")
		)
		(fp_rect
			(start -0.5842 1.3335)
			(end 0.5842 -1.3335)
			(stroke
				(width 0)
				(type default)
			)
			(fill no)
			(layer "F.CrtYd")
		)
		(fp_rect
			(start -0.5842 1.3335)
			(end 0.5842 -1.3335)
			(stroke
				(width 0)
				(type default)
			)
			(fill no)
			(layer "F.Fab")
		)
		(pad "1" smd custom
			(at 0 -0.762 90)
			(size 0.2159 0.2159)
			(layers "F.Cu" "F.Mask" "F.Paste")
			(net "HDD_PRSNT_24")
			(options
				(clearance outline)
				(anchor circle)
			)
			(primitives
				(gr_poly
					(pts
						(arc
							(start -0.3302 -0.4318)
							(mid -0.402042 -0.402042)
							(end -0.4318 -0.3302)
						)
						(arc
							(start -0.4318 0.3302)
							(mid -0.402042 0.402042)
							(end -0.3302 0.4318)
						)
						(arc
							(start 0.3302 0.4318)
							(mid 0.402042 0.402042)
							(end 0.4318 0.3302)
						)
						(arc
							(start 0.4318 -0.3302)
							(mid 0.402042 -0.402042)
							(end 0.3302 -0.4318)
						)
					)
					(width 0)
					(fill yes)
				)
			)
		)
		(pad "2" smd custom
			(at 0 0.762 90)
			(size 0.2159 0.2159)
			(layers "F.Cu" "F.Mask" "F.Paste")
			(net "DRIVE_A_24_INS")
			(options
				(clearance outline)
				(anchor circle)
			)
			(primitives
				(gr_poly
					(pts
						(arc
							(start -0.3302 -0.4318)
							(mid -0.402042 -0.402042)
							(end -0.4318 -0.3302)
						)
						(arc
							(start -0.4318 0.3302)
							(mid -0.402042 0.402042)
							(end -0.3302 0.4318)
						)
						(arc
							(start 0.3302 0.4318)
							(mid 0.402042 0.402042)
							(end 0.4318 0.3302)
						)
						(arc
							(start 0.4318 -0.3302)
							(mid 0.402042 -0.402042)
							(end 0.3302 -0.4318)
						)
					)
					(width 0)
					(fill yes)
				)
			)
		)
	)
	(footprint ""
		(layer "F.Cu")
		(at 400.03095 -45.735494 180)
		(property "Reference" "R879"
			(at 0 0 180)
			(layer "F.SilkS")
			(hide yes)
			(effects
				(font
					(size 1.27 1.27)
				)
			)
		)
		(property "Value" "4K7R2J-2-GP"
			(at 0.064008 -3.993896 180)
			(unlocked yes)
			(layer "F.Fab")
			(hide yes)
			(effects
				(font
					(size 1.016 1.016)
					(thickness 0.1524)
				)
			)
		)
		(property "Device Type" "R402H16"
			(at 0.064008 -5.517896 180)
			(unlocked yes)
			(layer "F.Fab")
			(hide yes)
			(effects
				(font
					(size 1.016 1.016)
					(thickness 0.1524)
				)
			)
		)
		(duplicate_pad_numbers_are_jumpers no)
		(fp_line
			(start 0.508 -0.9398)
			(end -0.508 -0.9398)
			(stroke
				(width 0.1524)
				(type default)
			)
			(layer "F.SilkS")
		)
		(fp_line
			(start -0.508 -0.9398)
			(end -0.508 0.9398)
			(stroke
				(width 0.1524)
				(type default)
			)
			(layer "F.SilkS")
		)
		(fp_rect
			(start -0.508 0.9398)
			(end 0.508 -0.9398)
			(stroke
				(width 0)
				(type default)
			)
			(fill no)
			(layer "F.CrtYd")
		)
		(fp_rect
			(start -0.508 0.9398)
			(end 0.508 -0.9398)
			(stroke
				(width 0)
				(type default)
			)
			(fill no)
			(layer "F.Fab")
		)
		(pad "1" smd custom
			(at 0 -0.4445 180)
			(size 0.1397 0.1397)
			(layers "F.Cu" "F.Mask" "F.Paste")
			(net "P12V_A")
			(options
				(clearance outline)
				(anchor circle)
			)
			(primitives
				(gr_poly
					(pts
						(arc
							(start -0.1778 -0.2794)
							(mid -0.249642 -0.249642)
							(end -0.2794 -0.1778)
						)
						(arc
							(start -0.2794 0.1778)
							(mid -0.249642 0.249642)
							(end -0.1778 0.2794)
						)
						(arc
							(start 0.1778 0.2794)
							(mid 0.249642 0.249642)
							(end 0.2794 0.1778)
						)
						(arc
							(start 0.2794 -0.1778)
							(mid 0.249642 -0.249642)
							(end 0.1778 -0.2794)
						)
					)
					(width 0)
					(fill yes)
				)
			)
		)
		(pad "2" smd custom
			(at 0 0.4445 180)
			(size 0.1397 0.1397)
			(layers "F.Cu" "F.Mask" "F.Paste")
			(net "SW_HDD_R32")
			(options
				(clearance outline)
				(anchor circle)
			)
			(primitives
				(gr_poly
					(pts
						(arc
							(start -0.1778 -0.2794)
							(mid -0.249642 -0.249642)
							(end -0.2794 -0.1778)
						)
						(arc
							(start -0.2794 0.1778)
							(mid -0.249642 0.249642)
							(end -0.1778 0.2794)
						)
						(arc
							(start 0.1778 0.2794)
							(mid 0.249642 0.249642)
							(end 0.2794 0.1778)
						)
						(arc
							(start 0.2794 -0.1778)
							(mid 0.249642 -0.249642)
							(end 0.1778 -0.2794)
						)
					)
					(width 0)
					(fill yes)
				)
			)
		)
	)
	(footprint ""
		(layer "F.Cu")
		(at 458.9399 -279.596342 90)
		(property "Reference" "C178"
			(at 0 0 90)
			(layer "F.SilkS")
			(hide yes)
			(effects
				(font
					(size 1.27 1.27)
				)
			)
		)
		(property "Value" "SCD033U25V2KX-GP"
			(at 1.1811 -2.7051 90)
			(unlocked yes)
			(layer "F.Fab")
			(hide yes)
			(effects
				(font
					(size 1.016 1.016)
					(thickness 0.1524)
				)
			)
		)
		(property "Device Type" "C402H22"
			(at 1.1811 -4.2291 90)
			(unlocked yes)
			(layer "F.Fab")
			(hide yes)
			(effects
				(font
					(size 1.016 1.016)
					(thickness 0.1524)
				)
			)
		)
		(duplicate_pad_numbers_are_jumpers no)
		(fp_rect
			(start -0.4318 0.9525)
			(end 0.4318 -0.9525)
			(stroke
				(width 0)
				(type default)
			)
			(fill no)
			(layer "F.CrtYd")
		)
		(fp_rect
			(start -0.4318 0.9525)
			(end 0.4318 -0.9525)
			(stroke
				(width 0)
				(type default)
			)
			(fill no)
			(layer "F.Fab")
		)
		(pad "1" smd custom
			(at 0 -0.4445 90)
			(size 0.1524 0.1524)
			(layers "F.Cu" "F.Mask" "F.Paste")
			(net "SW_HDD_P10")
			(options
				(clearance outline)
				(anchor circle)
			)
			(primitives
				(gr_poly
					(pts
						(arc
							(start 0.3048 -0.2032)
							(mid 0.275042 -0.275042)
							(end 0.2032 -0.3048)
						)
						(arc
							(start -0.2032 -0.3048)
							(mid -0.275042 -0.275042)
							(end -0.3048 -0.2032)
						)
						(arc
							(start -0.3048 0.2032)
							(mid -0.275042 0.275042)
							(end -0.2032 0.3048)
						)
						(arc
							(start 0.2032 0.3048)
							(mid 0.275042 0.275042)
							(end 0.3048 0.2032)
						)
					)
					(width 0)
					(fill yes)
				)
			)
		)
		(pad "2" smd custom
			(at 0 0.4445 90)
			(size 0.1524 0.1524)
			(layers "F.Cu" "F.Mask" "F.Paste")
			(net "GND")
			(options
				(clearance outline)
				(anchor circle)
			)
			(primitives
				(gr_poly
					(pts
						(arc
							(start 0.3048 -0.2032)
							(mid 0.275042 -0.275042)
							(end 0.2032 -0.3048)
						)
						(arc
							(start -0.2032 -0.3048)
							(mid -0.275042 -0.275042)
							(end -0.3048 -0.2032)
						)
						(arc
							(start -0.3048 0.2032)
							(mid -0.275042 0.275042)
							(end -0.2032 0.3048)
						)
						(arc
							(start 0.2032 0.3048)
							(mid 0.275042 0.275042)
							(end 0.3048 0.2032)
						)
					)
					(width 0)
					(fill yes)
				)
			)
		)
	)
	(footprint ""
		(layer "F.Cu")
		(at 318.4906 -298.704)
		(property "Reference" "TP32"
			(at 0 0 0)
			(layer "F.SilkS")
			(hide yes)
			(effects
				(font
					(size 1.27 1.27)
				)
			)
		)
		(property "Value" "TPAD32-GP"
			(at -0.0508 -1.6764 0)
			(unlocked yes)
			(layer "F.Fab")
			(hide yes)
			(effects
				(font
					(size 1.016 1.016)
					(thickness 0.1524)
				)
			)
		)
		(property "Device Type" "TPAD32"
			(at -0.0508 -3.2004 0)
			(unlocked yes)
			(layer "F.Fab")
			(hide yes)
			(effects
				(font
					(size 1.016 1.016)
					(thickness 0.1524)
				)
			)
		)
		(duplicate_pad_numbers_are_jumpers no)
		(fp_poly
			(pts
				(arc
					(start 0.4064 0)
					(mid -0.4064 0)
					(end 0.4064 0)
				)
			)
			(stroke
				(width 0)
				(type default)
			)
			(fill no)
			(layer "F.CrtYd")
		)
		(fp_poly
			(pts
				(arc
					(start 0.7112 0)
					(mid -0.7112 0)
					(end 0.7112 0)
				)
			)
			(stroke
				(width 0)
				(type default)
			)
			(fill no)
			(layer "F.Fab")
		)
		(pad "1" smd circle
			(at 0 0)
			(size 0.8128 0.8128)
			(layers "F.Cu" "F.Mask" "F.Paste")
			(net "ACT_HDD_6")
		)
	)
)
